# T6G (Grand Teton) — schematic parts with pin connectivity, parts 2658–2730 of 8303; source: Cadence DE-HDL packaged netlist (pstxprt.dat, pstxnet.dat, pstchip.dat)

J112  CONN160_10131762101LF  CONN160_10131762-101LF IO  pkg HSD_F160D8_P2W1-2_RDH  page 122
  A1  A1  BI  = RST_PERST_2_SWB_BUF_N
  A2  A2  BI  = GND
  A3  A3  BI  = HGX_DETECT_N_ISO
  A4  A4  BI  = GND
  A5  A5  BI  = RST_PERST_1_SWB_BUF_N
  A6  A6  BI  = GND
  A7  A7  BI  = PRSNT_SWB_N
  A8  A8  BI  = GND
  B1  B1  BI  = GND
  B2  B2  BI  = P5E_CPU1_P0_RX_BUF_DN<1>
  B3  B3  BI  = GND
  B4  B4  BI  = P5E_CPU1_P0_RX_BUF_DN<3>
  B5  B5  BI  = GND
  B6  B6  BI  = P5E_CPU1_P0_RX_BUF_DN<5>
  B7  B7  BI  = GND
  B8  B8  BI  = P5E_CPU1_P0_RX_BUF_DN<7>
  C1  C1  BI  = P5E_CPU1_P0_RX_BUF_DN<0>
  C2  C2  BI  = P5E_CPU1_P0_RX_BUF_DP<1>
  C3  C3  BI  = P5E_CPU1_P0_RX_BUF_DN<2>
  C4  C4  BI  = P5E_CPU1_P0_RX_BUF_DP<3>
  C5  C5  BI  = P5E_CPU1_P0_RX_BUF_DN<4>
  C6  C6  BI  = P5E_CPU1_P0_RX_BUF_DP<5>
  C7  C7  BI  = P5E_CPU1_P0_RX_BUF_DN<6>
  C8  C8  BI  = P5E_CPU1_P0_RX_BUF_DP<7>
  D1  D1  BI  = P5E_CPU1_P0_RX_BUF_DP<0>
  D2  D2  BI  = GND
  D3  D3  BI  = P5E_CPU1_P0_RX_BUF_DP<2>
  D4  D4  BI  = GND
  D5  D5  BI  = P5E_CPU1_P0_RX_BUF_DP<4>
  D6  D6  BI  = GND
  D7  D7  BI  = P5E_CPU1_P0_RX_BUF_DP<6>
  D8  D8  BI  = GND
  E1  E1  BI  = GND
  E2  E2  BI  = P5E_CPU1_P1_RX_BUF_DN<1>
  E3  E3  BI  = GND
  E4  E4  BI  = P5E_CPU1_P1_RX_BUF_DN<3>
  E5  E5  BI  = GND
  E6  E6  BI  = P5E_CPU1_P1_RX_BUF_DN<5>
  E7  E7  BI  = GND
  E8  E8  BI  = P5E_CPU1_P1_RX_BUF_DN<7>
  F1  F1  BI  = P5E_CPU1_P1_RX_BUF_DN<0>
  F2  F2  BI  = P5E_CPU1_P1_RX_BUF_DP<1>
  F3  F3  BI  = P5E_CPU1_P1_RX_BUF_DN<2>
  F4  F4  BI  = P5E_CPU1_P1_RX_BUF_DP<3>
  F5  F5  BI  = P5E_CPU1_P1_RX_BUF_DN<4>
  F6  F6  BI  = P5E_CPU1_P1_RX_BUF_DP<5>
  F7  F7  BI  = P5E_CPU1_P1_RX_BUF_DN<6>
  F8  F8  BI  = P5E_CPU1_P1_RX_BUF_DP<7>
  G1  G1  BI  = P5E_CPU1_P1_RX_BUF_DP<0>
  G2  G2  BI  = GND
  G3  G3  BI  = P5E_CPU1_P1_RX_BUF_DP<2>
  G4  G4  BI  = GND
  G5  G5  BI  = P5E_CPU1_P1_RX_BUF_DP<4>
  G6  G6  BI  = GND
  G7  G7  BI  = P5E_CPU1_P1_RX_BUF_DP<6>
  G8  G8  BI  = GND
  H1  H1  BI  = GND
  H2  H2  BI  = P5E_CPU1_P0_TX_BUF_C_DN<1>
  H3  H3  BI  = GND
  H4  H4  BI  = P5E_CPU1_P0_TX_BUF_C_DN<3>
  H5  H5  BI  = GND
  H6  H6  BI  = P5E_CPU1_P0_TX_BUF_C_DN<5>
  H7  H7  BI  = GND
  H8  H8  BI  = P5E_CPU1_P0_TX_BUF_C_DN<7>
  I1  I1  BI  = P5E_CPU1_P0_TX_BUF_C_DN<0>
  I2  I2  BI  = P5E_CPU1_P0_TX_BUF_C_DP<1>
  I3  I3  BI  = P5E_CPU1_P0_TX_BUF_C_DN<2>
  I4  I4  BI  = P5E_CPU1_P0_TX_BUF_C_DP<3>
  I5  I5  BI  = P5E_CPU1_P0_TX_BUF_C_DN<4>
  I6  I6  BI  = P5E_CPU1_P0_TX_BUF_C_DP<5>
  I7  I7  BI  = P5E_CPU1_P0_TX_BUF_C_DN<6>
  I8  I8  BI  = P5E_CPU1_P0_TX_BUF_C_DP<7>
  J1  J1  BI  = P5E_CPU1_P0_TX_BUF_C_DP<0>
  J2  J2  BI  = GND
  J3  J3  BI  = P5E_CPU1_P0_TX_BUF_C_DP<2>
  J4  J4  BI  = GND
  J5  J5  BI  = P5E_CPU1_P0_TX_BUF_C_DP<4>
  J6  J6  BI  = GND
  J7  J7  BI  = P5E_CPU1_P0_TX_BUF_C_DP<6>
  J8  J8  BI  = GND
  K1  K1  BI  = GND
  K2  K2  BI  = P5E_CPU1_P1_TX_BUF_C_DN<1>
  K3  K3  BI  = GND
  K4  K4  BI  = P5E_CPU1_P1_TX_BUF_C_DN<3>
  K5  K5  BI  = GND
  K6  K6  BI  = P5E_CPU1_P1_TX_BUF_C_DN<5>
  K7  K7  BI  = GND
  K8  K8  BI  = P5E_CPU1_P1_TX_BUF_C_DN<7>
  L1  L1  BI  = P5E_CPU1_P1_TX_BUF_C_DN<0>
  L2  L2  BI  = P5E_CPU1_P1_TX_BUF_C_DP<1>
  L3  L3  BI  = P5E_CPU1_P1_TX_BUF_C_DN<2>
  L4  L4  BI  = P5E_CPU1_P1_TX_BUF_C_DP<3>
  L5  L5  BI  = P5E_CPU1_P1_TX_BUF_C_DN<4>
  L6  L6  BI  = P5E_CPU1_P1_TX_BUF_C_DP<5>
  L7  L7  BI  = P5E_CPU1_P1_TX_BUF_C_DN<6>
  L8  L8  BI  = P5E_CPU1_P1_TX_BUF_C_DP<7>
  M1  M1  BI  = P5E_CPU1_P1_TX_BUF_C_DP<0>
  M2  M2  BI  = GND
  M3  M3  BI  = P5E_CPU1_P1_TX_BUF_C_DP<2>
  M4  M4  BI  = GND
  M5  M5  BI  = P5E_CPU1_P1_TX_BUF_C_DP<4>
  M6  M6  BI  = GND
  M7  M7  BI  = P5E_CPU1_P1_TX_BUF_C_DP<6>
  M8  M8  BI  = GND
  N1  N1  BI  = GND
  N2  N2  BI  = NC_J112_N2
  N3  N3  BI  = GND
  N4  N4  BI  = CLK_100M_CPU0_CLK11_DN
  N5  N5  BI  = GND
  N6  N6  BI  = P2E_MB_BMC_RX_DP<0>
  N7  N7  BI  = GND
  N8  N8  BI  = P3E_CPU1_P5_RX_DN<0>
  O1  O1  BI  = CLK_100M_CPU1_CLK01_DN
  O2  O2  BI  = NC_J112_O2
  O3  O3  BI  = CLK_100M_CPU1_CLK11_DN
  O4  O4  BI  = CLK_100M_CPU0_CLK11_DP
  O5  O5  BI  = NC_J112_O5
  O6  O6  BI  = P2E_MB_BMC_RX_DN<0>
  O7  O7  BI  = P3E_CPU1_P5_RX_DN<1>
  O8  O8  BI  = P3E_CPU1_P5_RX_DP<0>
  P1  P1  BI  = CLK_100M_CPU1_CLK01_DP
  P2  P2  BI  = GND
  P3  P3  BI  = CLK_100M_CPU1_CLK11_DP
  P4  P4  BI  = GND
  P5  P5  BI  = NC_J112_P5
  P6  P6  BI  = GND
  P7  P7  BI  = P3E_CPU1_P5_RX_DP<1>
  P8  P8  BI  = GND
  Q1  Q1  BI  = GND
  Q2  Q2  BI  = CLK_100M_GPU_FPGA_DN
  Q3  Q3  BI  = GND
  Q4  Q4  BI  = SMB_1_BMC_GPU_BUF_SCL
  Q5  Q5  BI  = GND
  Q6  Q6  BI  = P2E_MB_BMC_TX_BUF_C_DP<0>
  Q7  Q7  BI  = GND
  Q8  Q8  BI  = P3E_CPU1_P5_TX_C_DN<0>
  R1  R1  BI  = USB2_HUB_BUF_SWB_DN
  R2  R2  BI  = CLK_100M_GPU_FPGA_DP
  R3  R3  BI  = SMB_2_BMC_GPU_BUF_SCL
  R4  R4  BI  = SMB_1_BMC_GPU_BUF_SDA
  R5  R5  BI  = NC_J112_R5
  R6  R6  BI  = P2E_MB_BMC_TX_BUF_C_DN<0>
  R7  R7  BI  = P3E_CPU1_P5_TX_C_DP<1>
  R8  R8  BI  = P3E_CPU1_P5_TX_C_DP<0>
  S1  S1  BI  = USB2_HUB_BUF_SWB_DP
  S2  S2  BI  = GND
  S3  S3  BI  = SMB_2_BMC_GPU_BUF_SDA
  S4  S4  BI  = GND
  S5  S5  BI  = NC_J112_S5
  S6  S6  BI  = GND
  S7  S7  BI  = P3E_CPU1_P5_TX_C_DN<1>
  S8  S8  BI  = GND
  T1  T1  BI  = GND
  T2  T2  BI  = GPU_FPGA_READY
  T3  T3  BI  = GND
  T4  T4  BI  = GPU_NVS_PWR_BRAKE_N_BUF
  T5  T5  BI  = GND
  T6  T6  BI  = GPU_FPGA_THERM_OVERT_N
  T7  T7  BI  = GND
  T8  T8  BI  = RST_PERST_0_SWB_BUF_N

J114  PICOPROBE_BXA  DELTA-L 4.0 EMPTY  pkg TRIANG_LAUNCH_3PXB  page 229
  1  \1_p\  POWER  = DELTA_L_85_5INCH_IN5_DP
  2  \2_n\  POWER  = DELTA_L_85_5INCH_IN5_DN
  3  \3_g\  POWER  = DELTA_L_GND_1

J115  PICOPROBE_BXA  DELTA-L 4.0 EMPTY  pkg TRIANG_LAUNCH_3PXB  page 229
  1  \1_p\  POWER  = DELTA_L_85_5INCH_IN6_DP
  2  \2_n\  POWER  = DELTA_L_85_5INCH_IN6_DN
  3  \3_g\  POWER  = DELTA_L_GND_1

J116  PICOPROBE_BXA  DELTA-L 4.0 EMPTY  pkg TRIANG_LAUNCH_3PXB  page 229
  1  \1_p\  POWER  = DELTA_L_85_5INCH_IN5_DN
  2  \2_n\  POWER  = DELTA_L_85_5INCH_IN5_DP
  3  \3_g\  POWER  = DELTA_L_GND_1

J117  PICOPROBE_BXA  DELTA-L 4.0 EMPTY  pkg TRIANG_LAUNCH_3PXB  page 229
  1  \1_p\  POWER  = DELTA_L_85_5INCH_IN6_DN
  2  \2_n\  POWER  = DELTA_L_85_5INCH_IN6_DP
  3  \3_g\  POWER  = DELTA_L_GND_1

J118  PICOPROBE_BXA  DELTA-L 4.0 EMPTY  pkg TRIANG_LAUNCH_3PXB  page 229
  1  \1_p\  POWER  = DELTA_L_85_10INCH_IN5_DP
  2  \2_n\  POWER  = DELTA_L_85_10INCH_IN5_DN
  3  \3_g\  POWER  = DELTA_L_GND_1

J119  PICOPROBE_BXA  DELTA-L 4.0 EMPTY  pkg TRIANG_LAUNCH_3PXB  page 229
  1  \1_p\  POWER  = DELTA_L_85_10INCH_IN6_DP
  2  \2_n\  POWER  = DELTA_L_85_10INCH_IN6_DN
  3  \3_g\  POWER  = DELTA_L_GND_1

J120  PICOPROBE_BXA  DELTA-L 4.0 EMPTY  pkg TRIANG_LAUNCH_3PXB  page 229
  1  \1_p\  POWER  = DELTA_L_85_10INCH_IN5_DN
  2  \2_n\  POWER  = DELTA_L_85_10INCH_IN5_DP
  3  \3_g\  POWER  = DELTA_L_GND_1

J121  PICOPROBE_BXA  DELTA-L 4.0 EMPTY  pkg TRIANG_LAUNCH_3PXB  page 229
  1  \1_p\  POWER  = DELTA_L_85_10INCH_IN6_DN
  2  \2_n\  POWER  = DELTA_L_85_10INCH_IN6_DP
  3  \3_g\  POWER  = DELTA_L_GND_1

J122  CONN1_10165288101LF  CONN1_10165288-101LF IO  pkg CON_GUIDE-F1XG  page 230 : SCR_H1 = NC
J123  CONN1_10165288101LF  CONN1_10165288-101LF IO  pkg CON_GUIDE-F1XG  page 230 : SCR_H1 = NC

J212  CONN10_HBC1051L300D8H  CONN10_HBC1051-L300D-8H IO  pkg HEADER2X5XJ  page 27
  1  \1\  BI  = CPU0_XTRIG_L4
  2  \2\  BI  = CPU1_XTRIG_L4
  3  \3\  BI  = CPU0_XTRIG_L5
  4  \4\  BI  = CPU1_XTRIG_L5
  5  \5\  BI  = CPU0_XTRIG_L6
  6  \6\  BI  = CPU1_XTRIG_L6
  7  \7\  BI  = CPU0_XTRIG_L7
  8  \8\  BI  = CPU1_XTRIG_L7
  9  \9\  BI  = NC
  10  \10\  BI  = NC

J8067  PICOPROBE_BXA  DELTA-L 4.0 EMPTY  pkg TRIANG_LAUNCH_3PXB  page 229
  1  \1_p\  POWER  = DELTA_L_85_5INCH_IN3_DP
  2  \2_n\  POWER  = DELTA_L_85_5INCH_IN3_DN
  3  \3_g\  POWER  = DELTA_L_GND_1

J8068  PICOPROBE_BXA  DELTA-L 4.0 EMPTY  pkg TRIANG_LAUNCH_3PXB  page 229
  1  \1_p\  POWER  = DELTA_L_85_5INCH_IN4_DP
  2  \2_n\  POWER  = DELTA_L_85_5INCH_IN4_DN
  3  \3_g\  POWER  = DELTA_L_GND_1

J8069  PICOPROBE_BXA  DELTA-L 4.0 EMPTY  pkg TRIANG_LAUNCH_3PXB  page 229
  1  \1_p\  POWER  = DELTA_L_85_5INCH_TOP_DN
  2  \2_n\  POWER  = DELTA_L_85_5INCH_TOP_DP
  3  \3_g\  POWER  = DELTA_L_GND_1

JP10  CONN3_210HP1030BR1  CONN3_210-HP1-030BR1 IO  pkg HEADER1X3XG  page 268
  1  \1\  BI  = SMB_SML1_PMBUS_HSC_R1_SCL
  2  \2\  BI  = SMB_SML1_PMBUS_HSC_R1_SDA
  3  \3\  BI  = GND

JP12  CONN3_210HP1030BR1  CONN3_210-HP1-030BR1 IO  pkg HEADER1X3XG  page 187
  1  \1\  BI  = P1V5_BAT_OUT_R
  2  \2\  BI  = P1V5_BAT
  3  \3\  BI  = GND

JP4003  CONN3_210HP1030BR1  CONN3_210-HP1-030BR1 IO  pkg HEADER1X3XG  page 268
  1  \1\  BI  = NC
  2  \2\  BI  = PDB_PRSNT_R_N
  3  \3\  BI  = GND

JP6000  CONN3_210HP1030BR1  CONN3_210-HP1-030BR1 IO  pkg HEADER1X3XG  page 171
  1  \1\  BI  = PU_U212_EN_N
  2  \2\  BI  = U212_EN_N
  3  \3\  BI  = PD_U212_EN_N

JP6001  CONN3_210HP1030BR1  CONN3_210-HP1-030BR1 IO  pkg HEADER1X3XG  page 171
  1  \1\  BI  = PU_U160_EN_N
  2  \2\  BI  = U160_EN_N
  3  \3\  BI  = PD_U160_EN_N

JP6500  CONN3_210HP1030BR1  CONN3_210-HP1-030BR1 IO  pkg HEADER1X3XG  page 184
  1  \1\  BI  = SMB_MUX_RT_R2_SCL
  2  \2\  BI  = SMB_MUX_RT_R2_SDA
  3  \3\  BI  = GND

L1  Q_INDUCTOR  FCM2012KF-601T/0.5A IND  pkg SMLF  page 183 : 1 = P3V3_AUX ; 2 = P3V3_9ZXL045_P1
L2  Q_INDUCTOR  FCM2012KF-601T/0.5A IND  pkg SMLF  page 183 : 1 = P3V3_AUX ; 2 = P3V3_9ZXL045_P1_VDD
L3  Q_INDUCTOR  BLM21SN300SN1D/5A IND  pkg SMLF  page 323 : 1 = P1V8_CPU1_RT_1D ; 2 = P1V8_CPU1_RT0_1A
L4  Q_INDUCTOR  100NH/16A IND  pkg SMLF  page 323 : 1 = P0V9_CPU1_RT_2D ; 2 = P0V9_CPU1_RT0_2A
L5  Q_INDUCTOR  BLM21SN300SN1D/5A IND  pkg SMLF  page 334 : 1 = P1V8_CPU1_RT_1D ; 2 = P1V8_CPU1_RT1_1A
L6  Q_INDUCTOR  100NH/16A IND  pkg SMLF  page 334 : 1 = P0V9_CPU1_RT_2D ; 2 = P0V9_CPU1_RT1_2A
L7  Q_INDUCTOR  BLM21SN300SN1D/5A IND  pkg SMLF  page 345 : 1 = P1V8_CPU1_RT_1D ; 2 = P1V8_CPU1_RT2_1A
L8  Q_INDUCTOR  100NH/16A IND  pkg SMLF  page 345 : 1 = P0V9_CPU1_RT_2D ; 2 = P0V9_CPU1_RT2_2A
L9  Q_INDUCTOR  BLM21SN300SN1D/5A IND  pkg SMLF  page 356 : 1 = P1V8_CPU1_RT_1D ; 2 = P1V8_CPU1_RT3_1A
L10  Q_INDUCTOR  100NH/16A IND  pkg SMLF  page 356 : 1 = P0V9_CPU1_RT_2D ; 2 = P0V9_CPU1_RT3_2A
L11  Q_INDUCTOR  BLM21SN300SN1D/5A IND  pkg SMLF  page 279 : 1 = P1V8_CPU0_RT_1D ; 2 = P1V8_CPU0_RT0_1A
L12  Q_INDUCTOR  100NH/16A IND  pkg SMLF  page 279 : 1 = P0V9_CPU0_RT_2D ; 2 = P0V9_CPU0_RT0_2A
L13  Q_INDUCTOR  BLM21SN300SN1D/5A IND  pkg SMLF  page 290 : 1 = P1V8_CPU0_RT_1D ; 2 = P1V8_CPU0_RT1_1A
L14  Q_INDUCTOR  100NH/16A IND  pkg SMLF  page 290 : 1 = P0V9_CPU0_RT_2D ; 2 = P0V9_CPU0_RT1_2A
L15  Q_INDUCTOR  BLM18PG300SN1D IND  pkg SMLF  page 257 : 1 = P3V3_MAX11617_VDD ; 2 = P3V3_AUX
L16  Q_INDUCTOR  BLM18PG300SN1D IND  pkg SMLF  page 257 : 1 = P3V3_AUX ; 2 = P3V3_ADC128_VCC
L17  Q_INDUCTOR  FCM2012KF-601T/0.5A IND  pkg SMLF  page 233 : 1 = P3V3_AUX ; 2 = VFG3P3_CLK_GEN
L18  Q_INDUCTOR  BLM21SN300SN1D/5A IND  pkg SMLF  page 301 : 1 = P1V8_CPU0_RT_1D ; 2 = P1V8_CPU0_RT2_1A
L19  Q_INDUCTOR  FCM2012KF-601T/0.5A IND  pkg SMLF  page 182 : 1 = P3V3_AUX ; 2 = P3V3_9ZXL045_P0
L20  Q_INDUCTOR  FCM2012KF-601T/0.5A IND  pkg SMLF  page 182 : 1 = P3V3_AUX ; 2 = P3V3_9ZXL045_P0_VDD
L21  Q_INDUCTOR  100NH/16A IND  pkg SMLF  page 301 : 1 = P0V9_CPU0_RT_2D ; 2 = P0V9_CPU0_RT2_2A
L22  Q_INDUCTOR  BLM21SN300SN1D/5A IND  pkg SMLF  page 312 : 1 = P1V8_CPU0_RT_1D ; 2 = P1V8_CPU0_RT3_1A
L23  Q_INDUCTOR  100NH/16A IND  pkg SMLF  page 312 : 1 = P0V9_CPU0_RT_2D ; 2 = P0V9_CPU0_RT3_2A
L24  Q_INDUCTOR  BLM18PG300SN1D IND  pkg SMLF  page 258 : 1 = P3V3_MAX11617_2_VDD ; 2 = P3V3_AUX
L25  Q_INDUCTOR  BLM18PG300SN1D IND  pkg SMLF  page 258 : 1 = P3V3_AUX ; 2 = P3V3_ADC128_2_VCC
L26  Q_INDUCTOR  BLM15PD121SN1D/1300MA IND  pkg SMLF  page 279 : 1 = P1V8_CPU0_RT_1D ; 2 = P1V8_CPU0_RT0_1A_1D
L27  Q_INDUCTOR  BLM15PD121SN1D/1300MA IND  pkg SMLF  page 323 : 1 = P1V8_CPU1_RT_1D ; 2 = P1V8_CPU1_RT0_1A_1D
L28  Q_INDUCTOR  BLM15PD121SN1D/1300MA IND  pkg SMLF  page 290 : 1 = P1V8_CPU0_RT_1D ; 2 = P1V8_CPU0_RT1_1A_1D
L29  Q_INDUCTOR  BLM15PD121SN1D/1300MA IND  pkg SMLF  page 301 : 1 = P1V8_CPU0_RT_1D ; 2 = P1V8_CPU0_RT2_1A_1D
L30  Q_INDUCTOR  BLM15PD121SN1D/1300MA IND  pkg SMLF  page 312 : 1 = P1V8_CPU0_RT_1D ; 2 = P1V8_CPU0_RT3_1A_1D
L31  Q_INDUCTOR  BLM15PD121SN1D/1300MA IND  pkg SMLF  page 334 : 1 = P1V8_CPU1_RT_1D ; 2 = P1V8_CPU1_RT1_1A_1D
L32  Q_INDUCTOR  BLM15PD121SN1D/1300MA IND  pkg SMLF  page 345 : 1 = P1V8_CPU1_RT_1D ; 2 = P1V8_CPU1_RT2_1A_1D
L33  Q_INDUCTOR  BLM15PD121SN1D/1300MA IND  pkg SMLF  page 356 : 1 = P1V8_CPU1_RT_1D ; 2 = P1V8_CPU1_RT3_1A_1D
L6000  Q_INDUCTOR  BLM21PG221SN1D IND  pkg SMLF  page 177 : 1 = P3V3_AUX ; 2 = P3V3_AUX_CPU0_USB_AVDD33
L6001  Q_INDUCTOR  BLM21PG221SN1D IND  pkg SMLF  page 177 : 1 = P1V2_AUX ; 2 = P1V2_CPU0_USB_DVDD12
L6003  Q_INDUCTOR  BLM21PG221SN1D IND  pkg SMLF  page 179 : 1 = P3V3_AUX ; 2 = P3V3_AUX_CPU0_USB2_AVDD33
L6004  Q_INDUCTOR  BLM21PG221SN1D IND  pkg SMLF  page 179 : 1 = P1V2_AUX ; 2 = P1V2_CPU0_USB2_DVDD12

OSC1  Q_OSC4P  50MHZ OSC  pkg SMLF  page 133
  1  OE  IN  = CLK_50M_EN
  2  GND  POWER  = GND
  3  \out\  OUT  = CLK_50M_RMII
  4  VDD  POWER  = P3V3_AUX

PC3  Q_CAPP  270UF 16V 20% OSCON  pkg THLF  page 190 : 1 = SW_P3V3_AUX_FLT ; 2 = GND
PC4  Q_CAP  0.1UF 25V 10% X7R  pkg 0402  page 207 : 1 = PVDD11_S3_P0_VCC ; 2 = GND
PC5  Q_CAP  0.1UF 25V 10% X7R  pkg 0402  page 207 : 1 = PVDD11_S3_P0_VINSEN ; 2 = GND
PC6  Q_CAP  0.1UF 25V 10% X7R  pkg 0402  page 210 : 1 = PVDDCR_CPU0_P1_VINSEN ; 2 = GND
PC7  Q_CAP  0.1UF 25V 10% X7R  pkg 0402  page 193 : 1 = PVDDCR_CPU0_P0_VINSEN ; 2 = GND
PC8  Q_CAP  0.1UF 25V 10% X7R  pkg 0402  page 224 : 1 = PVDD11_S3_P1_VINSEN ; 2 = GND
PC9  Q_CAP  0.1UF 25V 10% X7R  pkg 0402  page 207 : 1 = PVDD11_S3_P0_VCCS ; 2 = GND
PC10  Q_CAP  0.1UF 25V 10% X7R  pkg 0402  page 210 : 1 = PVDDCR_CPU0_P1_VCC ; 2 = GND
PC11  Q_CAP  0.1UF 25V 10% X7R  pkg 0402  page 210 : 1 = PVDDCR_CPU0_P1_VCCS ; 2 = GND
PC12  Q_CAP  0.1UF 25V 10% X7R  pkg 0402  page 193 : 1 = PVDDCR_CPU0_P0_VCC ; 2 = GND
PC13  Q_CAP  0.1UF 25V 10% X7R  pkg 0402  page 193 : 1 = PVDDCR_CPU0_P0_VCCS ; 2 = GND
PC14  Q_CAP  0.1UF 25V 10% X7R  pkg 0402  page 200 : 1 = PVDDCR_CPU1_P0_VCC ; 2 = GND
PC15  Q_CAP  0.1UF 25V 10% X7R  pkg 0402  page 200 : 1 = PVDDCR_CPU1_P0_VCCS ; 2 = GND
PC19  Q_CAP  0.22UF 16V 10% X7R  pkg 0402  page 226 : 1 = SW_PVDD18_S5_P1_BST_R ; 2 = SW_PVDD18_S5_P1_SW
